(kicad_pcb
	(version 20260206)
	(generator "pcbnew")
	(generator_version "10.0")
	(general
		(thickness 1.6)
		(legacy_teardrops no)
	)
	(paper "A4")
	(title_block
		(title "Bryce Canyon_IOM_M2_16342-2_OCP.brd")
		(comment 1 "Bryce Canyon / footprints 32-34 of 1146")
	)
	(layers
		(0 "F.Cu" signal "TOP")
		(4 "In1.Cu" signal "L2GND")
		(6 "In2.Cu" signal "L3")
		(8 "In3.Cu" signal "L4VCC")
		(10 "In4.Cu" signal "L5VCC")
		(12 "In5.Cu" signal "L6")
		(14 "In6.Cu" signal "L7GND")
		(2 "B.Cu" signal "BOTTOM")
		(9 "F.Adhes" user "F.Adhesive")
		(11 "B.Adhes" user "B.Adhesive")
		(13 "F.Paste" user "Package Geometry/Pastemask Top")
		(15 "B.Paste" user "Package Geometry/Pastemask Bottom")
		(5 "F.SilkS" user "Ref Des/Silkscreen Top")
		(7 "B.SilkS" user "Ref Des/Silkscreen Bottom")
		(1 "F.Mask" user "Board Geometry/Soldermask Top")
		(3 "B.Mask" user "Board Geometry/Soldermask Bottom")
		(17 "Dwgs.User" user "User.Drawings")
		(19 "Cmts.User" user "User.Comments")
		(21 "Eco1.User" user "User.Eco1")
		(23 "Eco2.User" user "User.Eco2")
		(25 "Edge.Cuts" user "Board Geometry/Outline")
		(27 "Margin" user)
		(31 "F.CrtYd" user "Package Geometry/Place Bound Top")
		(29 "B.CrtYd" user "Package Geometry/Place Bound Bottom")
		(35 "F.Fab" user "Ref Des/Assembly Top")
		(33 "B.Fab" user "Ref Des/Assembly Bottom")
	)
	(footprint ""
		(layer "F.Cu")
		(at 88.9 -12.649962)
		(property "Reference" "USB1"
			(at 0 0 0)
			(layer "F.SilkS")
			(hide yes)
			(effects
				(font
					(size 1.27 1.27)
				)
			)
		)
		(property "Value" "SKT-USB13-246-GP"
			(at 4.9149 11.7348 0)
			(unlocked yes)
			(layer "F.Fab")
			(hide yes)
			(effects
				(font
					(size 1.016 1.016)
					(thickness 0.1524)
				)
			)
		)
		(property "Device Type" "SKT-USB13-064258"
			(at 4.9149 10.2108 0)
			(unlocked yes)
			(layer "F.Fab")
			(hide yes)
			(effects
				(font
					(size 1.016 1.016)
					(thickness 0.1524)
				)
			)
		)
		(duplicate_pad_numbers_are_jumpers no)
		(fp_line
			(start -3.827526 -10.395204)
			(end -3.827526 -11.004804)
			(stroke
				(width 0.3048)
				(type default)
			)
			(layer "F.SilkS")
		)
		(fp_line
			(start -3.827526 0.6477)
			(end -3.827526 -0.6477)
			(stroke
				(width 0.3048)
				(type default)
			)
			(layer "F.SilkS")
		)
		(fp_line
			(start -3.7211 -12.8016)
			(end 3.7211 -12.8016)
			(stroke
				(width 0.1524)
				(type default)
			)
			(layer "F.SilkS")
		)
		(fp_line
			(start -3.7211 -9.5758)
			(end -3.7211 -12.8016)
			(stroke
				(width 0.1524)
				(type default)
			)
			(layer "F.SilkS")
		)
		(fp_line
			(start -3.7211 -1.4732)
			(end -3.4671 -1.4732)
			(stroke
				(width 0.1524)
				(type default)
			)
			(layer "F.SilkS")
		)
		(fp_line
			(start -3.7211 1.4732)
			(end -3.7211 -1.4732)
			(stroke
				(width 0.1524)
				(type default)
			)
			(layer "F.SilkS")
		)
		(fp_line
			(start -3.4671 -9.5758)
			(end -3.7211 -9.5758)
			(stroke
				(width 0.1524)
				(type default)
			)
			(layer "F.SilkS")
		)
		(fp_line
			(start -3.4671 -1.4732)
			(end -3.4671 -9.5758)
			(stroke
				(width 0.1524)
				(type default)
			)
			(layer "F.SilkS")
		)
		(fp_line
			(start -3.4671 1.4732)
			(end -3.7211 1.4732)
			(stroke
				(width 0.1524)
				(type default)
			)
			(layer "F.SilkS")
		)
		(fp_line
			(start -3.4671 12.649962)
			(end -3.4671 1.4732)
			(stroke
				(width 0.1524)
				(type default)
			)
			(layer "F.SilkS")
		)
		(fp_line
			(start -3.4671 13.462)
			(end -3.4671 12.649962)
			(stroke
				(width 0.1524)
				(type default)
			)
			(layer "F.SilkS")
		)
		(fp_line
			(start -1.592326 -11.004804)
			(end -1.592326 -10.395204)
			(stroke
				(width 0.3048)
				(type default)
			)
			(layer "F.SilkS")
		)
		(fp_line
			(start -1.592326 -0.6477)
			(end -1.592326 0.6477)
			(stroke
				(width 0.3048)
				(type default)
			)
			(layer "F.SilkS")
		)
		(fp_line
			(start 1.592326 -10.052304)
			(end 1.592326 -11.347704)
			(stroke
				(width 0.3048)
				(type default)
			)
			(layer "F.SilkS")
		)
		(fp_line
			(start 1.592326 0.3048)
			(end 1.592326 -0.3048)
			(stroke
				(width 0.3048)
				(type default)
			)
			(layer "F.SilkS")
		)
		(fp_line
			(start 3.4671 -9.2202)
			(end 3.4671 -1.1303)
			(stroke
				(width 0.1524)
				(type default)
			)
			(layer "F.SilkS")
		)
		(fp_line
			(start 3.4671 -1.1303)
			(end 3.7211 -1.1303)
			(stroke
				(width 0.1524)
				(type default)
			)
			(layer "F.SilkS")
		)
		(fp_line
			(start 3.4671 1.1303)
			(end 3.4671 12.649962)
			(stroke
				(width 0.1524)
				(type default)
			)
			(layer "F.SilkS")
		)
		(fp_line
			(start 3.4671 12.649962)
			(end -3.4671 12.649962)
			(stroke
				(width 0.1524)
				(type default)
			)
			(layer "F.SilkS")
		)
		(fp_line
			(start 3.4671 12.649962)
			(end 3.4671 13.462)
			(stroke
				(width 0.1524)
				(type default)
			)
			(layer "F.SilkS")
		)
		(fp_line
			(start 3.4671 13.462)
			(end -3.4671 13.462)
			(stroke
				(width 0.1524)
				(type default)
			)
			(layer "F.SilkS")
		)
		(fp_line
			(start 3.7211 -12.8016)
			(end 3.7211 -9.2202)
			(stroke
				(width 0.1524)
				(type default)
			)
			(layer "F.SilkS")
		)
		(fp_line
			(start 3.7211 -9.2202)
			(end 3.4671 -9.2202)
			(stroke
				(width 0.1524)
				(type default)
			)
			(layer "F.SilkS")
		)
		(fp_line
			(start 3.7211 -1.1303)
			(end 3.7211 1.1303)
			(stroke
				(width 0.1524)
				(type default)
			)
			(layer "F.SilkS")
		)
		(fp_line
			(start 3.7211 1.1303)
			(end 3.4671 1.1303)
			(stroke
				(width 0.1524)
				(type default)
			)
			(layer "F.SilkS")
		)
		(fp_line
			(start 3.827526 -11.347704)
			(end 3.827526 -10.052304)
			(stroke
				(width 0.3048)
				(type default)
			)
			(layer "F.SilkS")
		)
		(fp_line
			(start 3.827526 -0.3048)
			(end 3.827526 0.3048)
			(stroke
				(width 0.3048)
				(type default)
			)
			(layer "F.SilkS")
		)
		(fp_arc
			(start -3.827526 -11.004804)
			(mid -2.709926 -12.122404)
			(end -1.592326 -11.004804)
			(stroke
				(width 0.3048)
				(type default)
			)
			(layer "F.SilkS")
		)
		(fp_arc
			(start -3.827526 -0.6477)
			(mid -2.709926 -1.7653)
			(end -1.592326 -0.6477)
			(stroke
				(width 0.3048)
				(type default)
			)
			(layer "F.SilkS")
		)
		(fp_arc
			(start -1.592326 -10.395204)
			(mid -2.709926 -9.277604)
			(end -3.827526 -10.395204)
			(stroke
				(width 0.3048)
				(type default)
			)
			(layer "F.SilkS")
		)
		(fp_arc
			(start -1.592326 0.6477)
			(mid -2.709926 1.7653)
			(end -3.827526 0.6477)
			(stroke
				(width 0.3048)
				(type default)
			)
			(layer "F.SilkS")
		)
		(fp_arc
			(start 1.592326 -11.347704)
			(mid 2.709926 -12.465304)
			(end 3.827526 -11.347704)
			(stroke
				(width 0.3048)
				(type default)
			)
			(layer "F.SilkS")
		)
		(fp_arc
			(start 1.592326 -0.3048)
			(mid 2.709926 -1.4224)
			(end 3.827526 -0.3048)
			(stroke
				(width 0.3048)
				(type default)
			)
			(layer "F.SilkS")
		)
		(fp_arc
			(start 1.607566 -9.8679)
			(mid 1.596126 -9.959786)
			(end 1.592326 -10.052304)
			(stroke
				(width 0.3048)
				(type default)
			)
			(layer "F.SilkS")
		)
		(fp_arc
			(start 1.783588 -9.426956)
			(mid 0.074258 -9.000444)
			(end 1.607566 -9.8679)
			(stroke
				(width 0.3048)
				(type default)
			)
			(layer "F.SilkS")
		)
		(fp_arc
			(start 3.827526 -10.052304)
			(mid 3.036889 -8.983601)
			(end 1.783588 -9.426956)
			(stroke
				(width 0.3048)
				(type default)
			)
			(layer "F.SilkS")
		)
		(fp_arc
			(start 3.827526 0.3048)
			(mid 2.709926 1.4224)
			(end 1.592326 0.3048)
			(stroke
				(width 0.3048)
				(type default)
			)
			(layer "F.SilkS")
		)
		(fp_circle
			(center -0.899922 -8.830056)
			(end -0.010922 -8.830056)
			(stroke
				(width 0.3048)
				(type default)
			)
			(fill no)
			(layer "F.SilkS")
		)
		(fp_circle
			(center -0.899922 -6.329934)
			(end -0.010922 -6.329934)
			(stroke
				(width 0.3048)
				(type default)
			)
			(fill no)
			(layer "F.SilkS")
		)
		(fp_circle
			(center -0.899922 -4.329938)
			(end -0.010922 -4.329938)
			(stroke
				(width 0.3048)
				(type default)
			)
			(fill no)
			(layer "F.SilkS")
		)
		(fp_circle
			(center -0.899922 -1.829816)
			(end -0.010922 -1.829816)
			(stroke
				(width 0.3048)
				(type default)
			)
			(fill no)
			(layer "F.SilkS")
		)
		(fp_circle
			(center -0.899922 -1.829816)
			(end -0.010922 -1.829816)
			(stroke
				(width 0.3048)
				(type default)
			)
			(fill no)
			(layer "F.SilkS")
		)
		(fp_circle
			(center 0.899922 -7.329932)
			(end 1.788922 -7.329932)
			(stroke
				(width 0.3048)
				(type default)
			)
			(fill no)
			(layer "F.SilkS")
		)
		(fp_circle
			(center 0.899922 -5.329936)
			(end 1.788922 -5.329936)
			(stroke
				(width 0.3048)
				(type default)
			)
			(fill no)
			(layer "F.SilkS")
		)
		(fp_circle
			(center 0.899922 -3.32994)
			(end 1.788922 -3.32994)
			(stroke
				(width 0.3048)
				(type default)
			)
			(fill no)
			(layer "F.SilkS")
		)
		(fp_circle
			(center 0.899922 -1.329944)
			(end 1.788922 -1.329944)
			(stroke
				(width 0.3048)
				(type default)
			)
			(fill no)
			(layer "F.SilkS")
		)
		(fp_circle
			(center 0.899922 -1.329944)
			(end 1.788922 -1.329944)
			(stroke
				(width 0.3048)
				(type default)
			)
			(fill no)
			(layer "F.SilkS")
		)
		(fp_rect
			(start -3.2131 13.208)
			(end 3.2131 -12.5476)
			(stroke
				(width 0)
				(type default)
			)
			(fill no)
			(layer "F.CrtYd")
		)
		(fp_poly
			(pts
				(xy -3.7211 13.716) (xy -3.7211 1.7272) (xy -3.9751 1.7272) (xy -3.9751 -1.7272) (xy -3.7211 -1.7272)
				(xy -3.7211 -9.3218) (xy -3.9751 -9.3218) (xy -3.9751 -13.0556) (xy 3.9751 -13.0556) (xy 3.9751 -8.9662)
				(xy 3.7211 -8.9662) (xy 3.7211 -1.3843) (xy 3.9751 -1.3843) (xy 3.9751 -0.00635) (xy 3.2131 -0.00635)
				(xy 3.2131 -12.5476) (xy -3.2131 -12.5476) (xy -3.2131 13.208) (xy 3.2131 13.208) (xy 3.2131 0.00635)
				(xy 3.9751 0.00635) (xy 3.9751 1.3843) (xy 3.7211 1.3843) (xy 3.7211 13.716)
			)
			(stroke
				(width 0)
				(type default)
			)
			(fill no)
			(layer "F.CrtYd")
		)
		(fp_poly
			(pts
				(xy -3.7211 13.716) (xy -3.7211 1.7272) (xy -3.9751 1.7272) (xy -3.9751 -1.7272) (xy -3.7211 -1.7272)
				(xy -3.7211 -9.3218) (xy -3.9751 -9.3218) (xy -3.9751 -13.0556) (xy 3.9751 -13.0556) (xy 3.9751 -8.9662)
				(xy 3.7211 -8.9662) (xy 3.7211 -1.3843) (xy 3.9751 -1.3843) (xy 3.9751 1.3843) (xy 3.7211 1.3843)
				(xy 3.7211 13.716)
			)
			(stroke
				(width 0)
				(type default)
			)
			(fill no)
			(layer "F.Fab")
		)
		(pad "1" thru_hole circle
			(at -0.899922 -8.830056)
			(size 1.0668 1.0668)
			(drill 0.7112)
			(layers "*.Cu" "*.Mask")
			(remove_unused_layers no)
			(net "P5V_VBUS_CONN")
			(clearance 0.1778)
			(thermal_gap 0.1778)
		)
		(pad "2" thru_hole circle
			(at -0.899922 -6.329934)
			(size 1.0668 1.0668)
			(drill 0.7112)
			(layers "*.Cu" "*.Mask")
			(remove_unused_layers no)
			(net "USB_P1_F_DN1")
			(clearance 0.1778)
			(thermal_gap 0.1778)
		)
		(pad "3" thru_hole circle
			(at -0.899922 -4.329938)
			(size 1.0668 1.0668)
			(drill 0.7112)
			(layers "*.Cu" "*.Mask")
			(remove_unused_layers no)
			(net "USB_P1_F_DP1")
			(clearance 0.1778)
			(thermal_gap 0.1778)
		)
		(pad "4" thru_hole circle
			(at -0.899922 -1.829816)
			(size 1.0668 1.0668)
			(drill 0.7112)
			(layers "*.Cu" "*.Mask")
			(remove_unused_layers no)
			(net "GND")
			(clearance 0.1778)
			(thermal_gap 0.1778)
		)
		(pad "5" thru_hole circle
			(at 0.899922 -1.329944)
			(size 1.0668 1.0668)
			(drill 0.7112)
			(layers "*.Cu" "*.Mask")
			(remove_unused_layers no)
			(net "I2C_DEBUG_SCL")
			(clearance 0.1778)
			(thermal_gap 0.1778)
		)
		(pad "6" thru_hole circle
			(at 0.899922 -3.32994)
			(size 1.0668 1.0668)
			(drill 0.7112)
			(layers "*.Cu" "*.Mask")
			(remove_unused_layers no)
			(net "I2C_DEBUG_SDA")
			(clearance 0.1778)
			(thermal_gap 0.1778)
		)
		(pad "7" thru_hole circle
			(at 0.899922 -5.329936)
			(size 1.0668 1.0668)
			(drill 0.7112)
			(layers "*.Cu" "*.Mask")
			(remove_unused_layers no)
			(net "DEBUG_CARD_PRSNT")
			(clearance 0.1778)
			(thermal_gap 0.1778)
		)
		(pad "8" thru_hole circle
			(at 0.899922 -7.329932)
			(size 1.0668 1.0668)
			(drill 0.7112)
			(layers "*.Cu" "*.Mask")
			(remove_unused_layers no)
			(net "UART_IOM_TX")
			(clearance 0.1778)
			(thermal_gap 0.1778)
		)
		(pad "9" thru_hole circle
			(at 0.899922 -9.329928)
			(size 1.0668 1.0668)
			(drill 0.7112)
			(layers "*.Cu" "*.Mask")
			(remove_unused_layers no)
			(net "UART_IOM_RX")
			(clearance 0.1778)
			(thermal_gap 0.1778)
		)
		(pad "10" thru_hole oval
			(at -2.709926 -10.700004)
			(size 1.524 2.1336)
			(drill oval 0.8128 1.4224)
			(layers "*.Cu" "*.Mask")
			(remove_unused_layers no)
			(net "USB_CONN_GND")
			(clearance 0.1524)
			(thermal_gap 0.1524)
		)
		(pad "11" thru_hole oval
			(at -2.709926 0)
			(size 1.524 2.8194)
			(drill oval 0.8128 2.1082)
			(layers "*.Cu" "*.Mask")
			(remove_unused_layers no)
			(net "USB_CONN_GND")
			(clearance 0.1524)
			(thermal_gap 0.1524)
		)
		(pad "12" thru_hole oval
			(at 2.709926 0)
			(size 1.524 2.1336)
			(drill oval 0.8128 1.4224)
			(layers "*.Cu" "*.Mask")
			(remove_unused_layers no)
			(net "USB_CONN_GND")
			(clearance 0.1524)
			(thermal_gap 0.1524)
		)
		(pad "13" thru_hole oval
			(at 2.709926 -10.700004)
			(size 1.524 2.8194)
			(drill oval 0.8128 2.1082)
			(layers "*.Cu" "*.Mask")
			(remove_unused_layers no)
			(net "USB_CONN_GND")
			(clearance 0.1524)
			(thermal_gap 0.1524)
		)
	)
	(footprint ""
		(layer "F.Cu")
		(at 27.559 -124.206)
		(property "Reference" "R787"
			(at 0 0 0)
			(layer "F.SilkS")
			(hide yes)
			(effects
				(font
					(size 1.27 1.27)
				)
			)
		)
		(property "Value" "0R2J-2-GP"
			(at 0.064008 -3.993896 0)
			(unlocked yes)
			(layer "F.Fab")
			(hide yes)
			(effects
				(font
					(size 1.016 1.016)
					(thickness 0.1524)
				)
			)
		)
		(property "Device Type" "R402H16"
			(at 0.064008 -5.517896 0)
			(unlocked yes)
			(layer "F.Fab")
			(hide yes)
			(effects
				(font
					(size 1.016 1.016)
					(thickness 0.1524)
				)
			)
		)
		(duplicate_pad_numbers_are_jumpers no)
		(fp_line
			(start -0.508 -0.9398)
			(end -0.508 0.9398)
			(stroke
				(width 0.1524)
				(type default)
			)
			(layer "F.SilkS")
		)
		(fp_line
			(start 0.508 -0.9398)
			(end -0.508 -0.9398)
			(stroke
				(width 0.1524)
				(type default)
			)
			(layer "F.SilkS")
		)
		(fp_rect
			(start -0.508 0.9398)
			(end 0.508 -0.9398)
			(stroke
				(width 0)
				(type default)
			)
			(fill no)
			(layer "F.CrtYd")
		)
		(fp_rect
			(start -0.508 0.9398)
			(end 0.508 -0.9398)
			(stroke
				(width 0)
				(type default)
			)
			(fill no)
			(layer "F.Fab")
		)
		(pad "1" smd custom
			(at 0 -0.4445)
			(size 0.1397 0.1397)
			(layers "F.Cu" "F.Mask" "F.Paste")
			(net "FLA0_WP_N")
			(options
				(clearance outline)
				(anchor circle)
			)
			(primitives
				(gr_poly
					(pts
						(arc
							(start -0.1778 -0.2794)
							(mid -0.249642 -0.249642)
							(end -0.2794 -0.1778)
						)
						(arc
							(start -0.2794 0.1778)
							(mid -0.249642 0.249642)
							(end -0.1778 0.2794)
						)
						(arc
							(start 0.1778 0.2794)
							(mid 0.249642 0.249642)
							(end 0.2794 0.1778)
						)
						(arc
							(start 0.2794 -0.1778)
							(mid 0.249642 -0.249642)
							(end 0.1778 -0.2794)
						)
					)
					(width 0)
					(fill yes)
				)
			)
		)
		(pad "2" smd custom
			(at 0 0.4445)
			(size 0.1397 0.1397)
			(layers "F.Cu" "F.Mask" "F.Paste")
			(net "WP_DISABLE")
			(options
				(clearance outline)
				(anchor circle)
			)
			(primitives
				(gr_poly
					(pts
						(arc
							(start -0.1778 -0.2794)
							(mid -0.249642 -0.249642)
							(end -0.2794 -0.1778)
						)
						(arc
							(start -0.2794 0.1778)
							(mid -0.249642 0.249642)
							(end -0.1778 0.2794)
						)
						(arc
							(start 0.1778 0.2794)
							(mid 0.249642 0.249642)
							(end 0.2794 0.1778)
						)
						(arc
							(start 0.2794 -0.1778)
							(mid 0.249642 -0.249642)
							(end 0.1778 -0.2794)
						)
					)
					(width 0)
					(fill yes)
				)
			)
		)
	)
	(footprint ""
		(layer "F.Cu")
		(at 131.768088 -6.77672 -90)
		(property "Reference" "R450"
			(at 0 0 270)
			(layer "F.SilkS")
			(hide yes)
			(effects
				(font
					(size 1.27 1.27)
				)
			)
		)
		(property "Value" "10R5F-1-GP"
			(at 0 -8.9535 270)
			(unlocked yes)
			(layer "F.Fab")
			(hide yes)
			(effects
				(font
					(size 1.27 1.016)
					(thickness 0.1524)
				)
			)
		)
		(property "Device Type" "R805H24"
			(at 0 -10.6299 270)
			(unlocked yes)
			(layer "F.Fab")
			(hide yes)
			(effects
				(font
					(size 1.27 1.016)
					(thickness 0.1524)
				)
			)
		)
		(duplicate_pad_numbers_are_jumpers no)
		(fp_line
			(start -0.889 1.7018)
			(end 0.889 1.7018)
			(stroke
				(width 0.1524)
				(type default)
			)
			(layer "F.SilkS")
		)
		(fp_line
			(start 0.889 1.7018)
			(end 0.889 -0.508)
			(stroke
				(width 0.1524)
				(type default)
			)
			(layer "F.SilkS")
		)
		(fp_line
			(start -0.889 0.0762)
			(end -0.889 1.7018)
			(stroke
				(width 0.1524)
				(type default)
			)
			(layer "F.SilkS")
		)
		(fp_line
			(start -0.889 -1.7018)
			(end -0.889 0.2794)
			(stroke
				(width 0.1524)
				(type default)
			)
			(layer "F.SilkS")
		)
		(fp_line
			(start 0.889 -1.7018)
			(end 0.889 -0.381)
			(stroke
				(width 0.1524)
				(type default)
			)
			(layer "F.SilkS")
		)
		(fp_line
			(start 0.889 -1.7018)
			(end -0.889 -1.7018)
			(stroke
				(width 0.1524)
				(type default)
			)
			(layer "F.SilkS")
		)
		(fp_poly
			(pts
				(xy 0.9652 -1.778) (xy 0.9652 1.778) (xy -0.9652 1.778) (xy -0.9652 -1.778)
			)
			(stroke
				(width 0)
				(type default)
			)
			(fill no)
			(layer "F.CrtYd")
		)
		(fp_rect
			(start -0.9652 1.778)
			(end 0.9652 -1.778)
			(stroke
				(width 0)
				(type default)
			)
			(fill no)
			(layer "F.Fab")
		)
		(pad "1" smd rect
			(at 0 -0.9652 270)
			(size 1.397 1.143)
			(layers "F.Cu" "F.Mask" "F.Paste")
			(net "MB0_12V_CTRL_GATE1")
		)
		(pad "2" smd rect
			(at 0 0.9652 270)
			(size 1.397 1.143)
			(layers "F.Cu" "F.Mask" "F.Paste")
			(net "MB0_CM_GATE_R")
		)
	)
)
